Units used: mil

Designator Comment             Layer       Footprint                 Center-X(mil) Center-Y(mil) Rotation Description                                                                                                                    
D2         8240136             TopLayer    SOT143-4L                 553.150       2230.315      90       "TVS Diode WE-TVS-HS, VRWM=3.3V"                                                                                               
D1         8240136             TopLayer    SOT143-4L                 551.181       1171.260      90       "TVS Diode WE-TVS-HS, VRWM=3.3V"                                                                                               
R27        4.7K                TopLayer    RESC1608X55X30NL15T15     2372.047      2755.905      90       "Precision Thick Film Chip Resistor, 4.7 KOhm, +/- 1%, -55 to 155 degC, 0603 (1608 Metric), RoHS, Tape and Reel ERJ-3EKF4701V" 
R26        4.7K                TopLayer    RESC1608X55X30NL15T15     2431.102      2755.905      90       "Precision Thick Film Chip Resistor, 4.7 KOhm, +/- 1%, -55 to 155 degC, 0603 (1608 Metric), RoHS, Tape and Reel ERJ-3EKF4701V" 
P3         "AUX Sensor"        TopLayer    HDR1X4                    5286.221      4261.811      360      "Header, 4-Pin"                                                                                                                
U10        MAC-SA5X            TopLayer    SA53                      4753.937      1732.284      0        "MOD, MAC, MAC-SA5X, ATOMIC CLOCK"                                                                                             
R14        49.9R               TopLayer    RESC1608X55X25NL10T15     974.409       2509.843      270      "General Purpose Chip Resistor, 49.9 Ohm, +/- 1%, -55 to 155 degC, 0603 (1608 Metric), RoHS, Tape and Reel"                    
U14        BME280              TopLayer    FP-BME280-MFG             3533.465      2824.803      0        "SENSOR PRESSURE HUMIDITY TEMP"                                                                                                
U13        BMX160              TopLayer    FP-BMX160-MFG             3238.189      2824.803      0        "IMU ACCEL/GYRO/MAG"                                                                                                           
U12        NC7SZ125M5          TopLayer    FP-318BQ-MFG              1090.551      966.535       360      "IC BUF NON-INVERT 5.5V SOT23-5"                                                                                               
U11        NC7SZ125M5          TopLayer    FP-318BQ-MFG              1102.362      1968.504      180      "IC BUF NON-INVERT 5.5V SOT23-5"                                                                                               
U8         NC7SZ125M5          TopLayer    FP-318BQ-MFG              1092.520      1486.220      360      "IC BUF NON-INVERT 5.5V SOT23-5"                                                                                               
U6         NC7SZ125M5          TopLayer    FP-318BQ-MFG              1102.362      2500.000      180      "IC BUF NON-INVERT 5.5V SOT23-5"                                                                                               
U4         DS90LV028AQMA       TopLayer    M08A_L                    4744.095      2824.803      360      "Automotive LVDS Dual Differential Line Receiver, 8-pin Narrow SOIC"                                                           
U3         DS90LV027AQMA       TopLayer    M08A_N                    5448.819      2829.331      360      "Automotive LVDS Dual Differential Driver, 8-pin Narrow SOIC"                                                                  
R25        49.9R               TopLayer    RESC1608X55X25NL10T15     974.409       935.039       270      "General Purpose Chip Resistor, 49.9 Ohm, +/- 1%, -55 to 155 degC, 0603 (1608 Metric), RoHS, Tape and Reel"                    
R17        49.9R               TopLayer    RESC1608X55X25NL10T15     974.409       1988.189      270      "General Purpose Chip Resistor, 49.9 Ohm, +/- 1%, -55 to 155 degC, 0603 (1608 Metric), RoHS, Tape and Reel"                    
R13        49.9R               TopLayer    RESC1608X55X25NL10T15     4931.102      2814.961      270      "General Purpose Chip Resistor, 49.9 Ohm, +/- 1%, -55 to 155 degC, 0603 (1608 Metric), RoHS, Tape and Reel"                    
R12        110R                TopLayer    RESC1609X50X30NL10T20     4557.087      2874.016      270      ""                                                                                                                             
R11        4.7K                TopLayer    RESC1608X55X25LL10T15     5206.693      2775.591      360      "Chip Resistor, 4.7 KOhm, +/- 1%, 0.1 W, -55 to 155 degC, 0603 (1608 Metric), RoHS, Tape and Reel RC0603FR-074K7L"             
R10        4.7K                TopLayer    RESC1608X55X25LL10T15     5206.693      2854.331      360      "Chip Resistor, 4.7 KOhm, +/- 1%, 0.1 W, -55 to 155 degC, 0603 (1608 Metric), RoHS, Tape and Reel RC0603FR-074K7L"             
C33        0.1uF               TopLayer    CAPC1608X87X45ML20T05     3375.984      2724.409      90       C0603X104K5RACAUTO                                                                                                             
C32        0.1uF               TopLayer    CAPC1608X87X45ML20T05     3220.472      2696.850      180      C0603X104K5RACAUTO                                                                                                             
C31        0.1uF               TopLayer    CAPC1608X87X45ML20T05     3661.417      2925.197      270      C0603X104K5RACAUTO                                                                                                             
C30        0.1uF               TopLayer    CAPC1608X87X45ML20T05     3535.433      2952.756      180      C0603X104K5RACAUTO                                                                                                             
C29        0.1uF               TopLayer    CAPC1608X87X45ML20T05     1094.488      1614.173      180      C0603X104K5RACAUTO                                                                                                             
C28        0.1uF               TopLayer    CAPC1608X87X45ML20T05     1090.551      1104.331      180      C0603X104K5RACAUTO                                                                                                             
C27        0.1uF               TopLayer    CAPC1608X87X45ML20T05     1102.362      1840.551      0        C0603X104K5RACAUTO                                                                                                             
C26        0.1uF               TopLayer    CAPC1608X87X45ML20T05     1102.362      2372.047      0        C0603X104K5RACAUTO                                                                                                             
C24        0.1uF               TopLayer    CAPC1608X87X45ML20T05     5000.000      2864.173      270      C0603X104K5RACAUTO                                                                                                             
C23        0.1uF               TopLayer    CAPC1608X87X45ML20T05     5226.378      2923.228      360      C0603X104K5RACAUTO                                                                                                             
AN1        901-143-6RFX        TopLayer    AMPHENOL-901-143-6RFX     199.843       2481.063      180      "Coaxial connector, 50 Ohm, -65 to 165 degC, 5-Pin THD, RoHS, Bulk"                                                            
AN2        901-143-6RFX        TopLayer    AMPHENOL-901-143-6RFX     199.843       1956.063      180      "Coaxial connector, 50 Ohm, -65 to 165 degC, 5-Pin THD, RoHS, Bulk"                                                            
AN3        901-143-6RFX        TopLayer    AMPHENOL-901-143-6RFX     199.843       1431.063      180      "Coaxial connector, 50 Ohm, -65 to 165 degC, 5-Pin THD, RoHS, Bulk"                                                            
AN4        901-143-6RFX        TopLayer    AMPHENOL-901-143-6RFX     199.843       906.063       180      "Coaxial connector, 50 Ohm, -65 to 165 degC, 5-Pin THD, RoHS, Bulk"                                                            
J10        1909763-1           TopLayer    TECO-1909763-1_V          555.610       905.512       90       "Ultra Miniature Coaxial Connector Jack, 60 V, 50 Ohm, -40 to 90 degC, RoHS, Tape and Reel"                                    
J9         1909763-1           TopLayer    TECO-1909763-1_V          555.610       1433.071      90       "Ultra Miniature Coaxial Connector Jack, 60 V, 50 Ohm, -40 to 90 degC, RoHS, Tape and Reel"                                    
J6         1909763-1           TopLayer    TECO-1909763-1_V          555.610       2480.315      90       "Ultra Miniature Coaxial Connector Jack, 60 V, 50 Ohm, -40 to 90 degC, RoHS, Tape and Reel"                                    
J5         1909763-1           TopLayer    TECO-1909763-1_V          555.610       1952.756      90       "Ultra Miniature Coaxial Connector Jack, 60 V, 50 Ohm, -40 to 90 degC, RoHS, Tape and Reel"                                    
R37        10K                 TopLayer    RESC1608X55X30LL15T20     2962.598      2696.850      180      "Chip Resistor, 10 KOhm, +/- 1%, 0.1 W, -55 to 155 degC, 0603 (1608 Metric), RoHS, Tape and Reel RMCF0603FT10K0"               
U7         AT24MAC402-STUM-T   TopLayer    FP-5TS1-IPC_C             2982.284      2814.961      270      "IC EEPROM 2K I2C 1MHZ SOT23-5"                                                                                                
C25        0.1uF               TopLayer    CAPC1608X87X45ML20T05     2854.331      2814.961      270      C0603X104K5RACAUTO                                                                                                             
R16        "200 OHM"           TopLayer    RESC1608X55X30NL15T15     641.732       4078.740      90       ERJ-3EKF2000V                                                                                                                  
R15        49.9R               TopLayer    RESC1608X55X25NL10T15     974.409       1456.693      270      "General Purpose Chip Resistor, 49.9 Ohm, +/- 1%, -55 to 155 degC, 0603 (1608 Metric), RoHS, Tape and Reel"                    
R5         ERJ-3EKF2612V       TopLayer    RESC1608X50N              6122.842      2461.063      90       "RES, 26.1K, 1%, 1/10W, TF, 0603"                                                                                              
U9         RCB-F9T             TopLayer    GNSS                      2550.295      3503.937      360      "MOD, GPS"                                                                                                                     
U5         HTST-105-01-L-DV-A  TopLayer    SAMTEC_HTST-105-01-L-DV-A 1816.102      4086.102      360      "CONN, HDR, 2X5, VERT, 0.1IN  SHROUDED, SMT, HTSH SERIES"                                                                      
U2         MP1482DS-LF         TopLayer    SOIC127P600X175-8N        6254.842      2316.063      180      "IC, DC/DC, MP1482DS, >4.75VIN, 0.923-15V OUT, SOIC8"                                                                          
U1         MP1482DS-LF         TopLayer    SOIC127P600X175-8N        6734.842      1956.063      360      "IC, DC/DC, MP1482DS, >4.75VIN, 0.923-15V OUT, SOIC8"                                                                          
R30        "200 OHM"           TopLayer    RESC1608X55X30NL15T15     1248.032      4078.740      90       ERJ-3EKF2000V                                                                                                                  
R29        "200 OHM"           TopLayer    RESC1608X55X30NL15T15     1047.244      4078.740      90       ERJ-3EKF2000V                                                                                                                  
R28        "200 OHM"           TopLayer    RESC1608X55X30NL15T15     846.457       4078.740      90       ERJ-3EKF2000V                                                                                                                  
R24        ERJ-2GE0R00X        TopLayer    RESC1005X04N              3055.118      590.551       270      "RES, 0. OHM, 1%, 1/16W, TF, AEC-Q200, 0402"                                                                                   
R23        ERJ-2GE0R00X        TopLayer    RESC1005X04N              2503.937      590.551       270      "RES, 0. OHM, 1%, 1/16W, TF, AEC-Q200, 0402"                                                                                   
R22        ERJ-3EKF4701V       TopLayer    RESC1608X50N              1419.685      1515.748      180      "RES, 4.7K, 1%, 1/10W, TF, 0603"                                                                                               
R21        CRCW080533R0FKEA    TopLayer    RESC2012X50N              2017.716      3750.000      90       "RES, 33 OHM, 1%, 1/8W, TF, 0805"                                                                                              
R20        CRCW080533R0FKEA    TopLayer    RESC2012X50N              1811.024      3750.000      90       "RES, 33 OHM, 1%, 1/8W, TF, 0805"                                                                                              
R19        CRCW080533R0FKEA    TopLayer    RESC2012X50N              1712.598      3750.000      90       "RES, 33 OHM, 1%, 1/8W, TF, 0805"                                                                                              
R18        CRCW080533R0FKEA    TopLayer    RESC2012X50N              1614.173      3750.000      90       "RES, 33 OHM, 1%, 1/8W, TF, 0805"                                                                                              
R9         ERJ-3EKF2201V       TopLayer    RESC1608X50N              6003.937      2362.205      270      "RES, 2.2K, 1%, 1/10W, TF, 0603"                                                                                               
R8         ERJ-3EKF2201V       TopLayer    RESC1608X50N              7000.000      1905.512      90       "RES, 2.2K, 1%, 1/10W, TF, 0603"                                                                                               
R7         ERJ-3EKF1002V       TopLayer    RESC1608X50N              6338.583      2460.630      180      "RES, 10K, 1%, 1/10W, TF, 0603"                                                                                                
R6         ERJ-3EKF1002V       TopLayer    RESC1608X50N              6763.779      1818.898      360      "RES, 10K, 1%, 1/10W, TF, 0603"                                                                                                
R4         ERJ-3EKF4702V       TopLayer    RESC1608X50N              6869.842      1816.063      360      "RES, 47K, 1%, 1/10W, TF, 0603"                                                                                                
R3         ERJ-3EKF4702V       TopLayer    RESC1608X50N              6234.842      2156.063      270      "RES, 47K, 1%, 1/10W, TF, 0603"                                                                                                
R2         ERJ-3EKF4702V       TopLayer    RESC1608X50N              6749.842      2116.063      90       "RES, 47K, 1%, 1/10W, TF, 0603"                                                                                                
R1         ERJ-3EKF2000V       TopLayer    RESC1608X50N              6129.921      2834.646      90       "RES, 200 OHM, 1%, 1/10W, TF, 0603"                                                                                            
P2         PCIex4              TopLayer    PCIE_4LANE_EDGE           2446.850      147.545       360      "PCIE x4 Edge Connector,OrCAD Symbol,NC"                                                                                       
P1         FPGA_CONN           TopLayer    FPGA_CONN                 2633.900      1698.425      360      ""                                                                                                                             
L2         PM124SH-100M-RC     TopLayer    IND_PM124SH               6679.842      2611.063      270      "IND, PWR, 10.uH, 20%, 4A, 0.04DCR, 12.5X12.5MM, SHLD"                                                                         
L1         PM124SH-100M-RC     TopLayer    IND_PM124SH               6319.842      1651.063      90       "IND, PWR, 10.uH, 20%, 4A, 0.04DCR, 12.5X12.5MM, SHLD"                                                                         
F1         FUSE_0603_2.00A     TopLayer    FUSM1608X60N              1944.882      645.275       270      "FUSE SLOW 2.00A 32V M 0603"                                                                                                   
D14        RED                 TopLayer    DIOM1608X06N              1249.842      4226.063      90       "LED, RED, SML-LX0603, 635NM, 2V, 20MA, 0603"                                                                                  
D13        RED                 TopLayer    DIOM1608X06N              1048.176      4226.063      90       "LED, RED, SML-LX0603, 635NM, 2V, 20MA, 0603"                                                                                  
D12        RED                 TopLayer    DIOM1608X06N              846.509       4226.063      90       "LED, RED, SML-LX0603, 635NM, 2V, 20MA, 0603"                                                                                  
D11        RED                 TopLayer    DIOM1608X06N              644.842       4226.063      90       "LED, RED, SML-LX0603, 635NM, 2V, 20MA, 0603"                                                                                  
D8         BAT54SW             TopLayer    SOT65P210X110-3N          2091.535      3602.362      180      "DIO, SCHOTTKY, BAT54S, DUAL SERIES, 30V, 200MA, SC-70"                                                                        
D7         BAT54SW             TopLayer    SOT65P210X110-3N          1914.370      3602.362      180      "DIO, SCHOTTKY, BAT54S, DUAL SERIES, 30V, 200MA, SC-70"                                                                        
D6         BAT54SW             TopLayer    SOT65P210X110-3N          1732.283      3602.362      180      "DIO, SCHOTTKY, BAT54S, DUAL SERIES, 30V, 200MA, SC-70"                                                                        
D5         BAT54SW             TopLayer    SOT65P210X110-3N          1555.118      3602.362      180      "DIO, SCHOTTKY, BAT54S, DUAL SERIES, 30V, 200MA, SC-70"                                                                        
D4         RED                 TopLayer    DIOM1608X06N              6192.913      2850.394      270      "LED, RED, SML-LX0603, 635NM, 2V, 20MA, 0603"                                                                                  
D3         DFLZ39-TP           TopLayer    SODFL370X135-2N           1858.268      602.362       270      "DIO, ZENER, DFLZ39, 39V, 5%, 1W, SOD123FL"                                                                                    
C63        0.1uF               TopLayer    CAPC1608X87X45ML20T05     3587.598      645.669       360      C0603X104K5RACAUTO                                                                                                             
C62        CAP_0805_10UF_25V   TopLayer    CAPC2012X14N              3589.528      726.063       180      "CAP, CER, 10.UF, 25V, 10%, X5R, 0805"                                                                                         
C61        0.1uF               TopLayer    CAPC1608X87X45ML20T05     2706.693      3169.291      90       C0603X104K5RACAUTO                                                                                                             
C60        CAP_0805_10UF_25V   TopLayer    CAPC2012X14N              2618.110      3179.134      270      "CAP, CER, 10.UF, 25V, 10%, X5R, 0805"                                                                                         
C59        0.1uF               TopLayer    CAPC1608X87X45ML20T05     2864.173      3356.299      90       C0603X104K5RACAUTO                                                                                                             
C58        CAP_0805_10UF_25V   TopLayer    CAPC2012X14N              2952.756      3362.205      270      "CAP, CER, 10.UF, 25V, 10%, X5R, 0805"                                                                                         
C53        CAP_0402_0.1UF_50V  BottomLayer CAPC1005X06N              3019.843      346.063       90       "CAP, CER, 0.1UF, 50V, 10%, X7R, AEC-Q200, 0402"                                                                               
C52        CAP_0402_0.1UF_50V  BottomLayer CAPC1005X06N              2979.843      346.063       90       "CAP, CER, 0.1UF, 50V, 10%, X7R, AEC-Q200, 0402"                                                                               
C51        CAP_0402_0.1UF_50V  BottomLayer CAPC1005X06N              2854.843      346.063       90       "CAP, CER, 0.1UF, 50V, 10%, X7R, AEC-Q200, 0402"                                                                               
C50        CAP_0402_0.1UF_50V  BottomLayer CAPC1005X06N              2819.843      346.063       90       "CAP, CER, 0.1UF, 50V, 10%, X7R, AEC-Q200, 0402"                                                                               
C49        CAP_0402_0.1UF_50V  BottomLayer CAPC1005X06N              2704.843      346.063       90       "CAP, CER, 0.1UF, 50V, 10%, X7R, AEC-Q200, 0402"                                                                               
C48        CAP_0402_0.1UF_50V  BottomLayer CAPC1005X06N              2664.843      346.063       90       "CAP, CER, 0.1UF, 50V, 10%, X7R, AEC-Q200, 0402"                                                                               
C47        CAP_0402_0.1UF_50V  BottomLayer CAPC1005X06N              2511.843      346.063       90       "CAP, CER, 0.1UF, 50V, 10%, X7R, AEC-Q200, 0402"                                                                               
C46        CAP_0402_0.1UF_50V  BottomLayer CAPC1005X06N              2468.843      346.063       90       "CAP, CER, 0.1UF, 50V, 10%, X7R, AEC-Q200, 0402"                                                                               
C45        CAP_0402_0.1UF_50V  BottomLayer CAPC1005X06N              2389.843      346.063       90       "CAP, CER, 0.1UF, 50V, 10%, X7R, AEC-Q200, 0402"                                                                               
C44        CAP_0402_0.1UF_50V  BottomLayer CAPC1005X06N              2349.843      346.063       90       "CAP, CER, 0.1UF, 50V, 10%, X7R, AEC-Q200, 0402"                                                                               
C22        0.033uF             TopLayer    CAPC1608X90X35NL10T15     6064.842      2361.063      90       GCM188R71H333KA55D                                                                                                             
C21        0.1uF               TopLayer    CAPC1608X87X45ML20T05     6124.842      2171.063      360      C0603X104K5RACAUTO                                                                                                             
C20        0.033uF             TopLayer    CAPC1608X90X35NL10T15     6939.842      1906.063      270      GCM188R71H333KA55D                                                                                                             
C19        0.1uF               TopLayer    CAPC1608X87X45ML20T05     6874.842      2096.063      180      C0603X104K5RACAUTO                                                                                                             
C18        0.1uF               TopLayer    CAPC1608X87X45ML20T05     6659.842      1776.063      360      C0603X104K5RACAUTO                                                                                                             
C17        0.1uF               TopLayer    CAPC1608X87X45ML20T05     6659.842      1721.063      360      C0603X104K5RACAUTO                                                                                                             
C16        0.1uF               TopLayer    CAPC1608X87X45ML20T05     6659.842      1671.063      360      C0603X104K5RACAUTO                                                                                                             
C15        0.1uF               TopLayer    CAPC1608X87X45ML20T05     6659.842      1611.063      360      C0603X104K5RACAUTO                                                                                                             
C14        CAP_0805_10UF_25V   TopLayer    CAPC2012X14N              6664.842      1531.063      180      "CAP, CER, 10.UF, 25V, 10%, X5R, 0805"                                                                                         
C13        CAP_0805_10UF_25V   TopLayer    CAPC2012X14N              6664.842      1421.063      180      "CAP, CER, 10.UF, 25V, 10%, X5R, 0805"                                                                                         
C12        0.1uF               TopLayer    CAPC1608X87X45ML20T05     6342.520      2673.228      180      C0603X104K5RACAUTO                                                                                                             
C11        0.1uF               TopLayer    CAPC1608X87X45ML20T05     6342.520      2606.299      180      C0603X104K5RACAUTO                                                                                                             
C10        0.1uF               TopLayer    CAPC1608X87X45ML20T05     6342.520      2535.433      180      C0603X104K5RACAUTO                                                                                                             
C9         0.1uF               TopLayer    CAPC1608X87X45ML20T05     6342.520      2740.157      180      C0603X104K5RACAUTO                                                                                                             
C8         CAP_0805_10UF_25V   TopLayer    CAPC2012X14N              6362.205      2858.268      90       "CAP, CER, 10.UF, 25V, 10%, X5R, 0805"                                                                                         
C7         CAP_0805_10UF_25V   TopLayer    CAPC2012X14N              6275.591      2858.268      90       "CAP, CER, 10.UF, 25V, 10%, X5R, 0805"                                                                                         
C6         CAP_0805_10UF_25V   TopLayer    CAPC2012X14N              6659.842      2131.063      90       "CAP, CER, 10.UF, 25V, 10%, X5R, 0805"                                                                                         
C5         CAP_0805_10UF_25V   TopLayer    CAPC2012X14N              6334.842      2146.063      270      "CAP, CER, 10.UF, 25V, 10%, X5R, 0805"                                                                                         
C4         CAP_0603_0.01UF_50V TopLayer    CAPC1608X10N              6519.842      1986.063      270      "CAP, CER, 0.01UF, 50V, 10%, X7R, 0603"                                                                                        
C3         CAP_0603_0.01UF_50V TopLayer    CAPC1608X10N              6469.842      2271.063      90       "CAP, CER, 0.01UF, 50V, 10%, X7R, 0603"                                                                                        
C2         0.1uF               TopLayer    CAPC1608X87X45ML20T05     2106.299      657.480       270      C0603X104K5RACAUTO                                                                                                             
C1         CAP_0805_10UF_25V   TopLayer    CAPC2012X14N              2019.685      665.354       90       "CAP, CER, 10.UF, 25V, 10%, X5R, 0805"                                                                                         
